# S9S_MB_2U (Grand Teton) — schematic netlist excerpt (pin names and nets, part order shuffled) for the footprints in the layout excerpt that follows; sources: Cadence DE-HDL packaged netlist, KiCad conversion of 03242023_DA0F0TMBIJ0_F0T_Motherboard_J_brd_V01_OCP.brd

R609  Q_RES  1K 1% EMPTY  pkg 0402LF  page 199 : A = P3V3_AUX ; B = FM_ESPI_CS_SWIZZLE
R2807  Q_RES  4.7K 5% EMPTY  pkg 0402LF  page 245 : A = P3V3_AUX ; B = SMB_FAN_3V3AUX_BUF_SDA

(kicad_pcb
	(version 20260206)
	(generator "pcbnew")
	(generator_version "10.0")
	(general
		(thickness 1.6)
		(legacy_teardrops no)
	)
	(paper "A4")
	(title_block
		(title "03242023_DA0F0TMBIJ0_F0T_Motherboard_J_brd_V01_OCP.brd")
		(comment 1 "Grand Teton / footprints 4394-4395 of 6105")
	)
	(layers
		(0 "F.Cu" signal "TOP")
		(4 "In1.Cu" signal "GND")
		(6 "In2.Cu" signal "IN1")
		(8 "In3.Cu" signal "GND1")
		(10 "In4.Cu" signal "IN2")
		(12 "In5.Cu" signal "GND2")
		(14 "In6.Cu" signal "IN3")
		(16 "In7.Cu" signal "GND3")
		(18 "In8.Cu" signal "VCC")
		(20 "In9.Cu" signal "VCC1")
		(22 "In10.Cu" signal "GND4")
		(24 "In11.Cu" signal "IN4")
		(26 "In12.Cu" signal "GND5")
		(28 "In13.Cu" signal "IN5")
		(30 "In14.Cu" signal "GND6")
		(32 "In15.Cu" signal "IN6")
		(34 "In16.Cu" signal "GND7")
		(2 "B.Cu" signal "BOTTOM")
		(9 "F.Adhes" user "F.Adhesive")
		(11 "B.Adhes" user "B.Adhesive")
		(13 "F.Paste" user "Package Geometry/Pastemask Top")
		(15 "B.Paste" user "Package Geometry/Pastemask Bottom")
		(5 "F.SilkS" user "Ref Des/Silkscreen Top")
		(7 "B.SilkS" user "Ref Des/Silkscreen Bottom")
		(1 "F.Mask" user "Board Geometry/Soldermask Top")
		(3 "B.Mask" user "Board Geometry/Soldermask Bottom")
		(17 "Dwgs.User" user "User.Drawings")
		(19 "Cmts.User" user "User.Comments")
		(21 "Eco1.User" user "User.Eco1")
		(23 "Eco2.User" user "User.Eco2")
		(25 "Edge.Cuts" user "Board Geometry/Outline")
		(27 "Margin" user)
		(31 "F.CrtYd" user "Package Geometry/Place Bound Top")
		(29 "B.CrtYd" user "Package Geometry/Place Bound Bottom")
		(35 "F.Fab" user "Ref Des/Assembly Top")
		(33 "B.Fab" user "Ref Des/Assembly Bottom")
	)
	(footprint ""
		(layer "B.Cu")
		(at 328.092816 -28.852876 -90)
		(property "Reference" "R609"
			(at 0 0 90)
			(layer "B.SilkS")
			(hide yes)
			(effects
				(font
					(size 1.27 1.27)
				)
				(justify mirror)
			)
		)
		(property "Value" ""
			(at 0 0 90)
			(layer "B.Fab")
			(effects
				(font
					(size 1.27 1.27)
				)
				(justify mirror)
			)
		)
		(duplicate_pad_numbers_are_jumpers no)
		(fp_line
			(start -0.7874 0.4064)
			(end 0.7874 0.4064)
			(stroke
				(width 0.1524)
				(type default)
			)
			(layer "B.SilkS")
		)
		(fp_line
			(start 0.7874 0.4064)
			(end 0.7874 -0.4064)
			(stroke
				(width 0.1524)
				(type default)
			)
			(layer "B.SilkS")
		)
		(fp_line
			(start -0.7874 -0.4064)
			(end -0.7874 0.4064)
			(stroke
				(width 0.1524)
				(type default)
			)
			(layer "B.SilkS")
		)
		(fp_line
			(start 0.7874 -0.4064)
			(end -0.7874 -0.4064)
			(stroke
				(width 0.1524)
				(type default)
			)
			(layer "B.SilkS")
		)
		(fp_line
			(start -0.67945 0.3048)
			(end -0.120396 0.3048)
			(stroke
				(width 0.1)
				(type default)
			)
			(layer "B.Fab")
		)
		(fp_line
			(start -0.120396 0.3048)
			(end -0.120396 0.2794)
			(stroke
				(width 0.1)
				(type default)
			)
			(layer "B.Fab")
		)
		(fp_line
			(start 0.12065 0.3048)
			(end 0.67945 0.3048)
			(stroke
				(width 0.1)
				(type default)
			)
			(layer "B.Fab")
		)
		(fp_line
			(start 0.67945 0.3048)
			(end 0.67945 -0.305054)
			(stroke
				(width 0.1)
				(type default)
			)
			(layer "B.Fab")
		)
		(fp_line
			(start -0.120396 0.2794)
			(end 0.12065 0.2794)
			(stroke
				(width 0.1)
				(type default)
			)
			(layer "B.Fab")
		)
		(fp_line
			(start 0.12065 0.2794)
			(end 0.12065 0.3048)
			(stroke
				(width 0.1)
				(type default)
			)
			(layer "B.Fab")
		)
		(fp_line
			(start -0.12065 -0.2794)
			(end -0.12065 -0.3048)
			(stroke
				(width 0.1)
				(type default)
			)
			(layer "B.Fab")
		)
		(fp_line
			(start 0.12065 -0.2794)
			(end -0.12065 -0.2794)
			(stroke
				(width 0.1)
				(type default)
			)
			(layer "B.Fab")
		)
		(fp_line
			(start -0.67945 -0.3048)
			(end -0.67945 0.3048)
			(stroke
				(width 0.1)
				(type default)
			)
			(layer "B.Fab")
		)
		(fp_line
			(start -0.12065 -0.3048)
			(end -0.67945 -0.3048)
			(stroke
				(width 0.1)
				(type default)
			)
			(layer "B.Fab")
		)
		(fp_line
			(start 0.12065 -0.305054)
			(end 0.12065 -0.2794)
			(stroke
				(width 0.1)
				(type default)
			)
			(layer "B.Fab")
		)
		(fp_line
			(start 0.67945 -0.305054)
			(end 0.12065 -0.305054)
			(stroke
				(width 0.1)
				(type default)
			)
			(layer "B.Fab")
		)
		(pad "1" smd circle
			(at 0.40005 0 90)
			(size 0 0)
			(layers "B.Cu" "B.Mask" "B.Paste")
			(net "P3V3_AUX")
		)
		(pad "2" smd circle
			(at -0.40005 0 90)
			(size 0 0)
			(layers "B.Cu" "B.Mask" "B.Paste")
			(net "FM_ESPI_CS_SWIZZLE")
		)
	)
	(footprint ""
		(layer "B.Cu")
		(at 179.887626 -415.633154 -90)
		(property "Reference" "R2807"
			(at 0 0 90)
			(layer "B.SilkS")
			(hide yes)
			(effects
				(font
					(size 1.27 1.27)
				)
				(justify mirror)
			)
		)
		(property "Value" ""
			(at 0 0 90)
			(layer "B.Fab")
			(effects
				(font
					(size 1.27 1.27)
				)
				(justify mirror)
			)
		)
		(duplicate_pad_numbers_are_jumpers no)
		(fp_line
			(start -0.7874 0.4064)
			(end 0.7874 0.4064)
			(stroke
				(width 0.1524)
				(type default)
			)
			(layer "B.SilkS")
		)
		(fp_line
			(start 0.7874 0.4064)
			(end 0.7874 -0.4064)
			(stroke
				(width 0.1524)
				(type default)
			)
			(layer "B.SilkS")
		)
		(fp_line
			(start -0.7874 -0.4064)
			(end -0.7874 0.4064)
			(stroke
				(width 0.1524)
				(type default)
			)
			(layer "B.SilkS")
		)
		(fp_line
			(start 0.7874 -0.4064)
			(end -0.7874 -0.4064)
			(stroke
				(width 0.1524)
				(type default)
			)
			(layer "B.SilkS")
		)
		(fp_line
			(start -0.67945 0.3048)
			(end -0.120396 0.3048)
			(stroke
				(width 0.1)
				(type default)
			)
			(layer "B.Fab")
		)
		(fp_line
			(start -0.120396 0.3048)
			(end -0.120396 0.2794)
			(stroke
				(width 0.1)
				(type default)
			)
			(layer "B.Fab")
		)
		(fp_line
			(start 0.12065 0.3048)
			(end 0.67945 0.3048)
			(stroke
				(width 0.1)
				(type default)
			)
			(layer "B.Fab")
		)
		(fp_line
			(start 0.67945 0.3048)
			(end 0.67945 -0.305054)
			(stroke
				(width 0.1)
				(type default)
			)
			(layer "B.Fab")
		)
		(fp_line
			(start -0.120396 0.2794)
			(end 0.12065 0.2794)
			(stroke
				(width 0.1)
				(type default)
			)
			(layer "B.Fab")
		)
		(fp_line
			(start 0.12065 0.2794)
			(end 0.12065 0.3048)
			(stroke
				(width 0.1)
				(type default)
			)
			(layer "B.Fab")
		)
		(fp_line
			(start -0.12065 -0.2794)
			(end -0.12065 -0.3048)
			(stroke
				(width 0.1)
				(type default)
			)
			(layer "B.Fab")
		)
		(fp_line
			(start 0.12065 -0.2794)
			(end -0.12065 -0.2794)
			(stroke
				(width 0.1)
				(type default)
			)
			(layer "B.Fab")
		)
		(fp_line
			(start -0.67945 -0.3048)
			(end -0.67945 0.3048)
			(stroke
				(width 0.1)
				(type default)
			)
			(layer "B.Fab")
		)
		(fp_line
			(start -0.12065 -0.3048)
			(end -0.67945 -0.3048)
			(stroke
				(width 0.1)
				(type default)
			)
			(layer "B.Fab")
		)
		(fp_line
			(start 0.12065 -0.305054)
			(end 0.12065 -0.2794)
			(stroke
				(width 0.1)
				(type default)
			)
			(layer "B.Fab")
		)
		(fp_line
			(start 0.67945 -0.305054)
			(end 0.12065 -0.305054)
			(stroke
				(width 0.1)
				(type default)
			)
			(layer "B.Fab")
		)
		(pad "1" smd circle
			(at 0.40005 0 90)
			(size 0 0)
			(layers "B.Cu" "B.Mask" "B.Paste")
			(net "P3V3_AUX")
		)
		(pad "2" smd circle
			(at -0.40005 0 90)
			(size 0 0)
			(layers "B.Cu" "B.Mask" "B.Paste")
			(net "SMB_FAN_3V3AUX_BUF_SDA")
		)
	)
)
